(kicad_pcb
	(version 20241229)
	(generator "pcbnew")
	(generator_version "9.0")
	(general
		(thickness 1.61)
		(legacy_teardrops no)
	)
	(paper "A3")
	(title_block
		(title "RDIMM DDR5 Tester")
		(date "2026-05-21")
		(rev "2.2.0")
		(company "Antmicro")
		(comment 9 "footprints 435-439 of 796")
	)
	(layers
		(0 "F.Cu" signal)
		(4 "In1.Cu" power)
		(6 "In2.Cu" mixed)
		(8 "In3.Cu" power)
		(10 "In4.Cu" mixed)
		(12 "In5.Cu" power)
		(14 "In6.Cu" mixed)
		(16 "In7.Cu" power)
		(18 "In8.Cu" power)
		(20 "In9.Cu" mixed)
		(22 "In10.Cu" power)
		(2 "B.Cu" signal)
		(9 "F.Adhes" user "F.Adhesive")
		(11 "B.Adhes" user "B.Adhesive")
		(13 "F.Paste" user)
		(15 "B.Paste" user)
		(5 "F.SilkS" user "F.Silkscreen")
		(7 "B.SilkS" user "B.Silkscreen")
		(1 "F.Mask" user)
		(3 "B.Mask" user)
		(17 "Dwgs.User" user "User.Drawings")
		(19 "Cmts.User" user "User.Comments")
		(21 "Eco1.User" user "User.Eco1")
		(23 "Eco2.User" user "User.Eco2")
		(25 "Edge.Cuts" user)
		(27 "Margin" user)
		(31 "F.CrtYd" user "F.Courtyard")
		(29 "B.CrtYd" user "B.Courtyard")
		(35 "F.Fab" user)
		(33 "B.Fab" user)
	)
	(footprint "antmicro-footprints:R_0402_1005Metric"
		(layer "B.Cu")
		(at 240.12 175.975 180)
		(descr "Resistor SMD 0402")
		(tags "resistor SMD 0402")
		(property "Reference" "R143"
			(at -4.505 -0.4 0)
			(layer "B.SilkS")
			(effects
				(font
					(size 0.7 0.7)
					(thickness 0.15)
				)
				(justify left bottom mirror)
			)
		)
		(property "Value" "R_47k_0402"
			(at -1.011843 -1.772047 0)
			(layer "B.Fab")
			(effects
				(font
					(size 0.7 0.7)
					(thickness 0.15)
				)
				(justify left bottom mirror)
			)
		)
		(property "Datasheet" "https://www.bourns.com/docs/product-datasheets/cr.pdf"
			(at 0 0 180)
			(layer "F.Fab")
			(hide yes)
			(effects
				(font
					(size 1.27 1.27)
					(thickness 0.15)
				)
			)
		)
		(property "Manufacturer" "Bourns"
			(at 0 0 180)
			(unlocked yes)
			(layer "B.Fab")
			(hide yes)
			(effects
				(font
					(size 1 1)
					(thickness 0.15)
				)
				(justify mirror)
			)
		)
		(property "MPN" "CR0402-FX-4702GLF"
			(at 0 0 180)
			(unlocked yes)
			(layer "B.Fab")
			(hide yes)
			(effects
				(font
					(size 1 1)
					(thickness 0.15)
				)
				(justify mirror)
			)
		)
		(property "Val" "47k"
			(at 0 0 180)
			(unlocked yes)
			(layer "B.Fab")
			(hide yes)
			(effects
				(font
					(size 1 1)
					(thickness 0.15)
				)
				(justify mirror)
			)
		)
		(property "License" "Apache-2.0"
			(at 0 0 180)
			(unlocked yes)
			(layer "B.Fab")
			(hide yes)
			(effects
				(font
					(size 1 1)
					(thickness 0.15)
				)
				(justify mirror)
			)
		)
		(property "Author" "Antmicro"
			(at 0 0 180)
			(unlocked yes)
			(layer "B.Fab")
			(hide yes)
			(effects
				(font
					(size 1 1)
					(thickness 0.15)
				)
				(justify mirror)
			)
		)
		(property "Tolerance" "1%"
			(at 0 0 180)
			(unlocked yes)
			(layer "B.Fab")
			(hide yes)
			(effects
				(font
					(size 1 1)
					(thickness 0.15)
				)
				(justify mirror)
			)
		)
		(sheetname "/Supply/DC-DC AUX, MGT/")
		(sheetfile "dc-dc-aux-mgt.kicad_sch")
		(attr smd)
		(fp_rect
			(start -0.925 0.47)
			(end 0.925 -0.47)
			(stroke
				(width 0.05)
				(type default)
			)
			(fill no)
			(layer "B.CrtYd")
		)
		(fp_rect
			(start -0.5 0.25)
			(end 0.5 -0.25)
			(stroke
				(width 0.15)
				(type solid)
			)
			(fill no)
			(layer "B.Fab")
		)
		(fp_text user "${REFERENCE}"
			(at -0.95 -3.168 0)
			(layer "B.Fab")
			(effects
				(font
					(size 0.7 0.7)
					(thickness 0.15)
				)
				(justify left bottom mirror)
			)
		)
		(fp_text user "License: Apache-2.0"
			(at -0.95 -5.169 0)
			(layer "B.Fab")
			(effects
				(font
					(size 0.7 0.7)
					(thickness 0.15)
				)
				(justify left bottom mirror)
			)
		)
		(fp_text user "Author: Antmicro"
			(at -0.95 -4.169 0)
			(layer "B.Fab")
			(effects
				(font
					(size 0.7 0.7)
					(thickness 0.15)
				)
				(justify left bottom mirror)
			)
		)
		(pad "1" smd roundrect
			(at -0.48 0 180)
			(size 0.59 0.64)
			(layers "B.Cu" "B.Mask" "B.Paste")
			(roundrect_rratio 0.25)
			(net 711 "Net-(U3-~{ALERT})")
			(pintype "passive")
		)
		(pad "2" smd roundrect
			(at 0.48 0 180)
			(size 0.59 0.64)
			(layers "B.Cu" "B.Mask" "B.Paste")
			(roundrect_rratio 0.25)
			(net 38 "+3V3_AON")
			(pintype "passive")
		)
	)
	(footprint "antmicro-footprints:C_0402_1005Metric_EIA"
		(layer "B.Cu")
		(at 190 152.5 90)
		(descr "Capacitor SMD 0402 (1005 Metric), square (rectangular) end terminal, IPC_7351 nominal, (Body size source: IPC-SM-782 page 76, https://www.pcb-3d.com/wordpress/wp-content/uploads/ipc-sm-782a_amendment_1_and_2.pdf)")
		(tags "capacitor 0402")
		(property "Reference" "C69"
			(at 11.925 -30.625 270)
			(layer "B.SilkS")
			(effects
				(font
					(size 0.7 0.7)
					(thickness 0.15)
				)
				(justify left bottom mirror)
			)
		)
		(property "Value" "C_100n_0402"
			(at 0 -1.169 270)
			(layer "B.Fab")
			(effects
				(font
					(size 0.7 0.7)
					(thickness 0.15)
				)
				(justify left bottom mirror)
			)
		)
		(property "Datasheet" "https://www.murata.com/products/productdetail?partno=GRM155R61H104KE14%23"
			(at 0 0 90)
			(layer "F.Fab")
			(hide yes)
			(effects
				(font
					(size 1.27 1.27)
					(thickness 0.15)
				)
			)
		)
		(property "Manufacturer" "Murata"
			(at 0 0 90)
			(unlocked yes)
			(layer "B.Fab")
			(hide yes)
			(effects
				(font
					(size 1 1)
					(thickness 0.15)
				)
				(justify mirror)
			)
		)
		(property "MPN" "GRM155R61H104KE14D"
			(at 0 0 90)
			(unlocked yes)
			(layer "B.Fab")
			(hide yes)
			(effects
				(font
					(size 1 1)
					(thickness 0.15)
				)
				(justify mirror)
			)
		)
		(property "Val" "100n"
			(at 0 0 90)
			(unlocked yes)
			(layer "B.Fab")
			(hide yes)
			(effects
				(font
					(size 1 1)
					(thickness 0.15)
				)
				(justify mirror)
			)
		)
		(property "License" "Apache-2.0"
			(at 0 0 90)
			(unlocked yes)
			(layer "B.Fab")
			(hide yes)
			(effects
				(font
					(size 1 1)
					(thickness 0.15)
				)
				(justify mirror)
			)
		)
		(property "Author" "Antmicro"
			(at 0 0 90)
			(unlocked yes)
			(layer "B.Fab")
			(hide yes)
			(effects
				(font
					(size 1 1)
					(thickness 0.15)
				)
				(justify mirror)
			)
		)
		(property "Voltage" "50V"
			(at 0 0 90)
			(unlocked yes)
			(layer "B.Fab")
			(hide yes)
			(effects
				(font
					(size 1 1)
					(thickness 0.15)
				)
				(justify mirror)
			)
		)
		(property "Dielectric" "X5R"
			(at 0 0 90)
			(unlocked yes)
			(layer "B.Fab")
			(hide yes)
			(effects
				(font
					(size 1 1)
					(thickness 0.15)
				)
				(justify mirror)
			)
		)
		(sheetname "/FPGA Config/")
		(sheetfile "fpga-config.kicad_sch")
		(attr smd)
		(fp_rect
			(start -0.95 0.45)
			(end 0.95 -0.45)
			(stroke
				(width 0.05)
				(type default)
			)
			(fill no)
			(layer "B.CrtYd")
		)
		(fp_line
			(start 0.498 -0.248)
			(end -0.5 -0.248)
			(stroke
				(width 0.15)
				(type solid)
			)
			(layer "B.Fab")
		)
		(fp_line
			(start -0.5 -0.248)
			(end -0.5 0.25)
			(stroke
				(width 0.15)
				(type solid)
			)
			(layer "B.Fab")
		)
		(fp_line
			(start 0.498 0.25)
			(end 0.498 -0.248)
			(stroke
				(width 0.15)
				(type solid)
			)
			(layer "B.Fab")
		)
		(fp_line
			(start -0.5 0.25)
			(end 0.498 0.25)
			(stroke
				(width 0.15)
				(type solid)
			)
			(layer "B.Fab")
		)
		(fp_text user "${REFERENCE}"
			(at -0.9656 -3.169 270)
			(layer "B.Fab")
			(effects
				(font
					(size 0.7 0.7)
					(thickness 0.15)
				)
				(justify left bottom mirror)
			)
		)
		(fp_text user "License: Apache-2.0"
			(at -0.9656 -4.369 270)
			(layer "B.Fab")
			(effects
				(font
					(size 0.7 0.7)
					(thickness 0.15)
				)
				(justify left bottom mirror)
			)
		)
		(fp_text user "Author: Antmicro"
			(at -0.9656 -5.569 270)
			(layer "B.Fab")
			(effects
				(font
					(size 0.7 0.7)
					(thickness 0.15)
				)
				(justify left bottom mirror)
			)
		)
		(pad "1" smd roundrect
			(at -0.5 0)
			(size 0.6 0.6)
			(layers "B.Cu" "B.Mask" "B.Paste")
			(roundrect_rratio 0.25)
			(net 598 "/FPGA Config/VREFN")
			(pintype "passive")
		)
		(pad "2" smd roundrect
			(at 0.498 0 90)
			(size 0.6 0.6)
			(layers "B.Cu" "B.Mask" "B.Paste")
			(roundrect_rratio 0.25)
			(net 599 "/FPGA Config/VREFP")
			(pintype "passive")
		)
	)
	(footprint "antmicro-footprints:SC70-3"
		(layer "B.Cu")
		(at 114.755 104.85 180)
		(property "Reference" "Q4"
			(at -3.355 -0.334 0)
			(layer "B.SilkS")
			(effects
				(font
					(size 0.7 0.7)
					(thickness 0.15)
				)
				(justify left bottom mirror)
			)
		)
		(property "Value" "BSS138PW"
			(at 0 -2.3 0)
			(layer "B.Fab")
			(effects
				(font
					(size 0.7 0.7)
					(thickness 0.15)
				)
				(justify left bottom mirror)
			)
		)
		(property "Datasheet" "https://assets.nexperia.com/documents/data-sheet/BSS138PW.pdf"
			(at 0 0 180)
			(layer "F.Fab")
			(hide yes)
			(effects
				(font
					(size 1.27 1.27)
					(thickness 0.15)
				)
			)
		)
		(property "MPN" "BSS138PW"
			(at 0 0 180)
			(unlocked yes)
			(layer "B.Fab")
			(hide yes)
			(effects
				(font
					(size 1 1)
					(thickness 0.15)
				)
				(justify mirror)
			)
		)
		(property "Manufacturer" "Nexperia"
			(at 0 0 180)
			(unlocked yes)
			(layer "B.Fab")
			(hide yes)
			(effects
				(font
					(size 1 1)
					(thickness 0.15)
				)
				(justify mirror)
			)
		)
		(property "Author" "Antmicro"
			(at 0 0 180)
			(unlocked yes)
			(layer "B.Fab")
			(hide yes)
			(effects
				(font
					(size 1 1)
					(thickness 0.15)
				)
				(justify mirror)
			)
		)
		(property "License" "Apache-2.0"
			(at 0 0 180)
			(unlocked yes)
			(layer "B.Fab")
			(hide yes)
			(effects
				(font
					(size 1 1)
					(thickness 0.15)
				)
				(justify mirror)
			)
		)
		(sheetname "/FPGA banks HD/")
		(sheetfile "fpga-hd-banks.kicad_sch")
		(attr smd)
		(fp_line
			(start 0.627 0.6)
			(end 0.627 0.999)
			(stroke
				(width 0.15)
				(type solid)
			)
			(layer "B.SilkS")
		)
		(fp_line
			(start 0.627 -0.6)
			(end 0.627 -1.001)
			(stroke
				(width 0.15)
				(type solid)
			)
			(layer "B.SilkS")
		)
		(fp_line
			(start -0.3 1)
			(end 0.627 0.999)
			(stroke
				(width 0.15)
				(type solid)
			)
			(layer "B.SilkS")
		)
		(fp_line
			(start -0.3 -1)
			(end 0.627 -1.001)
			(stroke
				(width 0.15)
				(type solid)
			)
			(layer "B.SilkS")
		)
		(fp_line
			(start 1.4 0.4)
			(end 1.4 -0.4)
			(stroke
				(width 0.05)
				(type solid)
			)
			(layer "B.CrtYd")
		)
		(fp_line
			(start 1.4 -0.4)
			(end 0.9 -0.4)
			(stroke
				(width 0.05)
				(type solid)
			)
			(layer "B.CrtYd")
		)
		(fp_line
			(start 0.9 1.3)
			(end 0.9 0.4)
			(stroke
				(width 0.05)
				(type solid)
			)
			(layer "B.CrtYd")
		)
		(fp_line
			(start 0.9 0.4)
			(end 1.4 0.4)
			(stroke
				(width 0.05)
				(type solid)
			)
			(layer "B.CrtYd")
		)
		(fp_line
			(start 0.9 -0.4)
			(end 0.9 -1.3)
			(stroke
				(width 0.05)
				(type solid)
			)
			(layer "B.CrtYd")
		)
		(fp_line
			(start 0.9 -1.3)
			(end -0.9 -1.3)
			(stroke
				(width 0.05)
				(type solid)
			)
			(layer "B.CrtYd")
		)
		(fp_line
			(start -0.9 1.3)
			(end 0.9 1.3)
			(stroke
				(width 0.05)
				(type solid)
			)
			(layer "B.CrtYd")
		)
		(fp_line
			(start -0.9 1.3)
			(end -0.9 1)
			(stroke
				(width 0.05)
				(type solid)
			)
			(layer "B.CrtYd")
		)
		(fp_line
			(start -0.9 1)
			(end -1.4 1)
			(stroke
				(width 0.05)
				(type solid)
			)
			(layer "B.CrtYd")
		)
		(fp_line
			(start -0.9 -1)
			(end -1.4 -1)
			(stroke
				(width 0.05)
				(type solid)
			)
			(layer "B.CrtYd")
		)
		(fp_line
			(start -0.9 -1.3)
			(end -0.9 -1)
			(stroke
				(width 0.05)
				(type solid)
			)
			(layer "B.CrtYd")
		)
		(fp_line
			(start -1.4 -1)
			(end -1.4 1)
			(stroke
				(width 0.05)
				(type solid)
			)
			(layer "B.CrtYd")
		)
		(fp_rect
			(start -0.623 0.999)
			(end 0.627 -1.001)
			(stroke
				(width 0.15)
				(type solid)
			)
			(fill no)
			(layer "B.Fab")
		)
		(fp_text user "${REFERENCE}"
			(at -1.45 -4.783 0)
			(layer "B.Fab")
			(effects
				(font
					(size 0.7 0.7)
					(thickness 0.15)
				)
				(justify left bottom mirror)
			)
		)
		(fp_text user "Author: Antmicro"
			(at -1.45 -5.782 0)
			(layer "B.Fab")
			(effects
				(font
					(size 0.7 0.7)
					(thickness 0.15)
				)
				(justify left bottom mirror)
			)
		)
		(fp_text user "License: Apache-2.0"
			(at -1.45 -6.782 0)
			(layer "B.Fab")
			(effects
				(font
					(size 0.7 0.7)
					(thickness 0.15)
				)
				(justify left bottom mirror)
			)
		)
		(pad "1" smd rect
			(at -1.051 0.65 90)
			(size 0.6 0.6)
			(layers "B.Cu" "B.Mask" "B.Paste")
			(net 701 "/FPGA banks HD/USR_LED5")
			(pinfunction "G")
			(pintype "passive")
		)
		(pad "2" smd rect
			(at -1.051 -0.65 90)
			(size 0.6 0.6)
			(layers "B.Cu" "B.Mask" "B.Paste")
			(net 1 "GND")
			(pinfunction "S")
			(pintype "passive")
		)
		(pad "3" smd rect
			(at 1.05 0 90)
			(size 0.6 0.6)
			(layers "B.Cu" "B.Mask" "B.Paste")
			(net 272 "Net-(Q4-D)")
			(pinfunction "D")
			(pintype "passive")
		)
	)
	(footprint "antmicro-footprints:R_0402_1005Metric"
		(layer "B.Cu")
		(at 238.424499 182.499 180)
		(descr "Resistor SMD 0402")
		(tags "resistor SMD 0402")
		(property "Reference" "R159"
			(at -3.95 -0.5 0)
			(layer "B.SilkS")
			(effects
				(font
					(size 0.7 0.7)
					(thickness 0.15)
				)
				(justify left bottom mirror)
			)
		)
		(property "Value" "R_4k7_0402"
			(at -1.011843 -1.772047 0)
			(layer "B.Fab")
			(effects
				(font
					(size 0.7 0.7)
					(thickness 0.15)
				)
				(justify left bottom mirror)
			)
		)
		(property "Datasheet" "https://www.bourns.com/docs/product-datasheets/cr.pdf"
			(at 0 0 180)
			(layer "F.Fab")
			(hide yes)
			(effects
				(font
					(size 1.27 1.27)
					(thickness 0.15)
				)
			)
		)
		(property "Manufacturer" "Bourns"
			(at 0 0 180)
			(unlocked yes)
			(layer "B.Fab")
			(hide yes)
			(effects
				(font
					(size 1 1)
					(thickness 0.15)
				)
				(justify mirror)
			)
		)
		(property "MPN" "CR0402-FX-4701GLF"
			(at 0 0 180)
			(unlocked yes)
			(layer "B.Fab")
			(hide yes)
			(effects
				(font
					(size 1 1)
					(thickness 0.15)
				)
				(justify mirror)
			)
		)
		(property "Val" "4k7"
			(at 0 0 180)
			(unlocked yes)
			(layer "B.Fab")
			(hide yes)
			(effects
				(font
					(size 1 1)
					(thickness 0.15)
				)
				(justify mirror)
			)
		)
		(property "License" "Apache-2.0"
			(at 0 0 180)
			(unlocked yes)
			(layer "B.Fab")
			(hide yes)
			(effects
				(font
					(size 1 1)
					(thickness 0.15)
				)
				(justify mirror)
			)
		)
		(property "Author" "Antmicro"
			(at 0 0 180)
			(unlocked yes)
			(layer "B.Fab")
			(hide yes)
			(effects
				(font
					(size 1 1)
					(thickness 0.15)
				)
				(justify mirror)
			)
		)
		(property "Tolerance" "1%"
			(at 0 0 180)
			(unlocked yes)
			(layer "B.Fab")
			(hide yes)
			(effects
				(font
					(size 1 1)
					(thickness 0.15)
				)
				(justify mirror)
			)
		)
		(sheetname "/I^{2}C + I3C/")
		(sheetfile "i2c.kicad_sch")
		(attr smd)
		(fp_rect
			(start -0.925 0.47)
			(end 0.925 -0.47)
			(stroke
				(width 0.05)
				(type default)
			)
			(fill no)
			(layer "B.CrtYd")
		)
		(fp_rect
			(start -0.5 0.25)
			(end 0.5 -0.25)
			(stroke
				(width 0.15)
				(type solid)
			)
			(fill no)
			(layer "B.Fab")
		)
		(fp_text user "${REFERENCE}"
			(at -0.95 -3.168 0)
			(layer "B.Fab")
			(effects
				(font
					(size 0.7 0.7)
					(thickness 0.15)
				)
				(justify left bottom mirror)
			)
		)
		(fp_text user "Author: Antmicro"
			(at -0.95 -4.169 0)
			(layer "B.Fab")
			(effects
				(font
					(size 0.7 0.7)
					(thickness 0.15)
				)
				(justify left bottom mirror)
			)
		)
		(fp_text user "License: Apache-2.0"
			(at -0.95 -5.169 0)
			(layer "B.Fab")
			(effects
				(font
					(size 0.7 0.7)
					(thickness 0.15)
				)
				(justify left bottom mirror)
			)
		)
		(pad "1" smd roundrect
			(at -0.48 0 180)
			(size 0.59 0.64)
			(layers "B.Cu" "B.Mask" "B.Paste")
			(roundrect_rratio 0.25)
			(net 151 "+3V3")
			(pintype "passive")
		)
		(pad "2" smd roundrect
			(at 0.48 0 180)
			(size 0.59 0.64)
			(layers "B.Cu" "B.Mask" "B.Paste")
			(roundrect_rratio 0.25)
			(net 747 "/FPGA Config/FPGA_PWR.SCL")
			(pintype "passive")
		)
	)
	(footprint "antmicro-footprints:R_0402_1005Metric"
		(layer "B.Cu")
		(at 238.774501 140.0975 180)
		(descr "Resistor SMD 0402")
		(tags "resistor SMD 0402")
		(property "Reference" "R139"
			(at -4.365499 -0.4225 0)
			(layer "B.SilkS")
			(effects
				(font
					(size 0.7 0.7)
					(thickness 0.15)
				)
				(justify left bottom mirror)
			)
		)
		(property "Value" "R_47k_0402"
			(at -1.011843 -1.772047 0)
			(layer "B.Fab")
			(effects
				(font
					(size 0.7 0.7)
					(thickness 0.15)
				)
				(justify left bottom mirror)
			)
		)
		(property "Datasheet" "https://www.bourns.com/docs/product-datasheets/cr.pdf"
			(at 0 0 180)
			(layer "F.Fab")
			(hide yes)
			(effects
				(font
					(size 1.27 1.27)
					(thickness 0.15)
				)
			)
		)
		(property "Manufacturer" "Bourns"
			(at 0 0 180)
			(unlocked yes)
			(layer "B.Fab")
			(hide yes)
			(effects
				(font
					(size 1 1)
					(thickness 0.15)
				)
				(justify mirror)
			)
		)
		(property "MPN" "CR0402-FX-4702GLF"
			(at 0 0 180)
			(unlocked yes)
			(layer "B.Fab")
			(hide yes)
			(effects
				(font
					(size 1 1)
					(thickness 0.15)
				)
				(justify mirror)
			)
		)
		(property "Val" "47k"
			(at 0 0 180)
			(unlocked yes)
			(layer "B.Fab")
			(hide yes)
			(effects
				(font
					(size 1 1)
					(thickness 0.15)
				)
				(justify mirror)
			)
		)
		(property "License" "Apache-2.0"
			(at 0 0 180)
			(unlocked yes)
			(layer "B.Fab")
			(hide yes)
			(effects
				(font
					(size 1 1)
					(thickness 0.15)
				)
				(justify mirror)
			)
		)
		(property "Author" "Antmicro"
			(at 0 0 180)
			(unlocked yes)
			(layer "B.Fab")
			(hide yes)
			(effects
				(font
					(size 1 1)
					(thickness 0.15)
				)
				(justify mirror)
			)
		)
		(property "Tolerance" "1%"
			(at 0 0 180)
			(unlocked yes)
			(layer "B.Fab")
			(hide yes)
			(effects
				(font
					(size 1 1)
					(thickness 0.15)
				)
				(justify mirror)
			)
		)
		(sheetname "/Supply/")
		(sheetfile "supply.kicad_sch")
		(attr smd)
		(fp_rect
			(start -0.925 0.47)
			(end 0.925 -0.47)
			(stroke
				(width 0.05)
				(type default)
			)
			(fill no)
			(layer "B.CrtYd")
		)
		(fp_rect
			(start -0.5 0.25)
			(end 0.5 -0.25)
			(stroke
				(width 0.15)
				(type solid)
			)
			(fill no)
			(layer "B.Fab")
		)
		(fp_text user "${REFERENCE}"
			(at -0.95 -3.168 0)
			(layer "B.Fab")
			(effects
				(font
					(size 0.7 0.7)
					(thickness 0.15)
				)
				(justify left bottom mirror)
			)
		)
		(fp_text user "Author: Antmicro"
			(at -0.95 -4.169 0)
			(layer "B.Fab")
			(effects
				(font
					(size 0.7 0.7)
					(thickness 0.15)
				)
				(justify left bottom mirror)
			)
		)
		(fp_text user "License: Apache-2.0"
			(at -0.95 -5.169 0)
			(layer "B.Fab")
			(effects
				(font
					(size 0.7 0.7)
					(thickness 0.15)
				)
				(justify left bottom mirror)
			)
		)
		(pad "1" smd roundrect
			(at -0.48 0 180)
			(size 0.59 0.64)
			(layers "B.Cu" "B.Mask" "B.Paste")
			(roundrect_rratio 0.25)
			(net 404 "IN1")
			(pintype "passive")
		)
		(pad "2" smd roundrect
			(at 0.48 0 180)
			(size 0.59 0.64)
			(layers "B.Cu" "B.Mask" "B.Paste")
			(roundrect_rratio 0.25)
			(net 38 "+3V3_AON")
			(pintype "passive")
		)
	)
)
